#  M.2 to OCuLink adapter — KiCad custom design rules (.kicad_dru)
(version 1)
#----------------------- PCIe -----------------------
(rule "(pcie_outer"
	(layer outer)
	(condition "(A.NetClass == '85Ohm-diff_PCIE')")
	(constraint track_width (opt 0.22mm))
	(constraint diff_pair_gap  (opt 0.11mm))
)
